# T6G (Grand Teton) — schematic netlist excerpt (pin names and nets, part order shuffled) for the footprints in the layout excerpt that follows; sources: Cadence DE-HDL packaged netlist, KiCad conversion of 04192023_DAF0TMB3IC0_F0TG_MB_C_brd_V02_OCP.brd

J67  SCONN288_DDR506112002KQ  IO  pkg DDR288S_1-1VXC  page 97
  VIN_BULK0  = P12V_MEM_CPU0
  RFU0  = NC
  VIN_MGMT  = P3V3_AUX
  HSCL  = I3C_SPD_DDRL_CPU0_SCL
  HSDA  = I3C_SPD_DDRL_CPU0_SDA
  VSS0  = GND
  DQ0_A  = M_L_CPU0_SA_DQ<0>
  VSS1  = GND
  DQ1_A  = M_L_CPU0_SA_DQ<1>
  VSS2  = GND
  DQS0_A_T  = M_L_CPU0_SA_DQS_DP<0>
  DQS0_A_C  = M_L_CPU0_SA_DQS_DN<0>
  VSS3  = GND
  DQ4_A  = M_L_CPU0_SA_DQ<4>
  VSS4  = GND
  DQ5_A  = M_L_CPU0_SA_DQ<5>
  VSS5  = GND
  DQ8_A  = M_L_CPU0_SA_DQ<8>
  VSS6  = GND
  DQ9_A  = M_L_CPU0_SA_DQ<9>
  VSS7  = GND
  DQS1_A_T  = M_L_CPU0_SA_DQS_DP<1>
  DQS1_A_C  = M_L_CPU0_SA_DQS_DN<1>
  VSS8  = GND
  DQ12_A  = M_L_CPU0_SA_DQ<12>
  VSS9  = GND
  DQ13_A  = M_L_CPU0_SA_DQ<13>
  VSS10  = GND
  DQ16_A  = M_L_CPU0_SA_DQ<16>
  VSS11  = GND
  DQ17_A  = M_L_CPU0_SA_DQ<17>
  VSS12  = GND
  DQS2_A_T  = M_L_CPU0_SA_DQS_DP<2>
  DQS2_A_C  = M_L_CPU0_SA_DQS_DN<2>
  VSS13  = GND
  DQ20_A  = M_L_CPU0_SA_DQ<20>
  VSS14  = GND
  DQ21_A  = M_L_CPU0_SA_DQ<21>
  VSS15  = GND
  DQ24_A  = M_L_CPU0_SA_DQ<24>
  VSS16  = GND
  DQ25_A  = M_L_CPU0_SA_DQ<25>
  VSS17  = GND
  DQS3_A_T  = M_L_CPU0_SA_DQS_DP<3>
  DQS3_A_C  = M_L_CPU0_SA_DQS_DN<3>
  VSS18  = GND
  DQ28_A  = M_L_CPU0_SA_DQ<28>
  VSS19  = GND
  DQ29_A  = M_L_CPU0_SA_DQ<29>
  VSS20  = GND
  CB0_A  = M_L_CPU0_SA_CB<0>
  VSS21  = GND
  CB1_A  = M_L_CPU0_SA_CB<1>
  VSS22  = GND
  DQS4_A_T  = M_L_CPU0_SA_DQS_DP<4>
  DQS4_A_C  = M_L_CPU0_SA_DQS_DN<4>
  VSS23  = GND
  CB4_A  = M_L_CPU0_SA_CB<4>
  VSS24  = GND
  CB5_A  = M_L_CPU0_SA_CB<5>
  VSS25  = GND
  ALERT_N  = M_L_CPU0_ALERT_N
  VSS26  = GND
  CS0_A_N  = M_L_CPU0_SA_CS_N<0>
  VSS27  = GND
  CA0_A  = M_L_CPU0_SA_CA<0>
  VSS28  = GND
  CA2_A  = M_L_CPU0_SA_CA<2>
  VSS29  = GND
  CA4_A  = M_L_CPU0_SA_CA<4>
  VSS30  = GND
  CA6_A  = M_L_CPU0_SA_CA<6>
  VSS31  = GND
  PAR_A  = M_L_CPU0_SA_PAR
  VSS32  = GND
  CA0_B  = M_L_CPU0_SB_CA<0>
  VSS33  = GND
  CA2_B  = M_L_CPU0_SB_CA<2>
  VSS34  = GND
  CA4_B  = M_L_CPU0_SB_CA<4>
  VSS35  = GND
  CA6_B  = M_L_CPU0_SB_CA<6>
  VSS36  = GND
  CS0_B_N  = M_L_CPU0_SB_CS_N<0>
  VSS37  = GND
  \lbd||rsp_a_n\  = M_L_CPU0_SA_RSP<0>
  \lbs||rsp_b_n\  = M_L_CPU0_SB_RSP<0>
  VSS38  = GND
  CB4_B  = M_L_CPU0_SB_CB<4>
  VSS39  = GND
  CB5_B  = M_L_CPU0_SB_CB<5>
  VSS40  = GND
  \dqs9_b_t||tdqs9_b_t||dbi4_b_n\  = M_L_CPU0_SB_DQS_DP<9>
  \dqs9_b_c||tdqs9_b_c\  = M_L_CPU0_SB_DQS_DN<9>
  VSS41  = GND
  CB0_B  = M_L_CPU0_SB_CB<0>
  VSS42  = GND
  CB1_B  = M_L_CPU0_SB_CB<1>
  VSS43  = GND
  DQ0_B  = M_L_CPU0_SB_DQ<0>
  VSS44  = GND
  DQ1_B  = M_L_CPU0_SB_DQ<1>
  VSS45  = GND
  DQS0_B_T  = M_L_CPU0_SB_DQS_DP<0>
  DQS0_B_C  = M_L_CPU0_SB_DQS_DN<0>
  VSS46  = GND
  DQ4_B  = M_L_CPU0_SB_DQ<4>
  VSS47  = GND
  DQ5_B  = M_L_CPU0_SB_DQ<5>
  VSS48  = GND
  DQ8_B  = M_L_CPU0_SB_DQ<8>
  VSS49  = GND
  DQ9_B  = M_L_CPU0_SB_DQ<9>
  VSS50  = GND
  DQS1_B_T  = M_L_CPU0_SB_DQS_DP<1>
  DQS1_B_C  = M_L_CPU0_SB_DQS_DN<1>
  VSS51  = GND
  DQ12_B  = M_L_CPU0_SB_DQ<12>
  VSS52  = GND
  DQ13_B  = M_L_CPU0_SB_DQ<13>
  VSS53  = GND
  DQ16_B  = M_L_CPU0_SB_DQ<16>
  VSS54  = GND
  DQ17_B  = M_L_CPU0_SB_DQ<17>
  VSS55  = GND
  DQS2_B_T  = M_L_CPU0_SB_DQS_DP<2>
  DQS2_B_C  = M_L_CPU0_SB_DQS_DN<2>
  VSS56  = GND
  DQ20_B  = M_L_CPU0_SB_DQ<20>
  VSS57  = GND
  DQ21_B  = M_L_CPU0_SB_DQ<21>
  VSS58  = GND
  DQ24_B  = M_L_CPU0_SB_DQ<24>
  VSS59  = GND
  DQ25_B  = M_L_CPU0_SB_DQ<25>
  VSS60  = GND
  DQS3_B_T  = M_L_CPU0_SB_DQS_DP<3>
  DQS3_B_C  = M_L_CPU0_SB_DQS_DN<3>
  VSS61  = GND
  DQ28_B  = M_L_CPU0_SB_DQ<28>
  VSS62  = GND
  DQ29_B  = M_L_CPU0_SB_DQ<29>
  VSS63  = GND
  RFU1  = NC
  VIN_BULK1  = P12V_MEM_CPU0
  VIN_BULK2  = P12V_MEM_CPU0
  \pwr_good||fail_n\  = PWRGD_CHL_CPU0_DIMM
  HAS  = PD_CHL_CPU0_DIMM_SAA
  RFU2  = NC
  RFU3  = NC
  VSS64  = GND
  DQ2_A  = M_L_CPU0_SA_DQ<2>
  VSS65  = GND
  DQ3_A  = M_L_CPU0_SA_DQ<3>
  VSS66  = GND
  \dqs5_a_c||tdqs5_a_c||dqs5_a_t||tdqs5_a_t\  = M_L_CPU0_SA_DQS_DN<5>
  \dqs5_a_t||tdqs5_a_t\  = M_L_CPU0_SA_DQS_DP<5>
  VSS67  = GND
  DQ6_A  = M_L_CPU0_SA_DQ<6>
  VSS68  = GND
  DQ7_A  = M_L_CPU0_SA_DQ<7>
  VSS69  = GND
  DQ10_A  = M_L_CPU0_SA_DQ<10>
  VSS70  = GND
  DQ11_A  = M_L_CPU0_SA_DQ<11>
  VSS71  = GND
  \dqs6_a_c||tdqs6_a_c||dqs6_a_t||tdqs6_a_t\  = M_L_CPU0_SA_DQS_DN<6>
  \dqs6_a_t||tdqs6_a_t\  = M_L_CPU0_SA_DQS_DP<6>
  VSS72  = GND
  DQ14_A  = M_L_CPU0_SA_DQ<14>
  VSS73  = GND
  DQ15_A  = M_L_CPU0_SA_DQ<15>
  VSS74  = GND
  DQ18_A  = M_L_CPU0_SA_DQ<18>
  VSS75  = GND
  DQ19_A  = M_L_CPU0_SA_DQ<19>
  VSS76  = GND
  \dqs7_a_c||tdqs7_a_c\  = M_L_CPU0_SA_DQS_DN<7>
  \dqs7_a_t||tdqs7_a_t\  = M_L_CPU0_SA_DQS_DP<7>
  VSS77  = GND
  DQ22_A  = M_L_CPU0_SA_DQ<22>
  VSS78  = GND
  DQ23_A  = M_L_CPU0_SA_DQ<23>
  VSS79  = GND
  DQ26_A  = M_L_CPU0_SA_DQ<26>
  VSS80  = GND
  DQ27_A  = M_L_CPU0_SA_DQ<27>
  VSS81  = GND
  \dqs8_a_c||tdqs8_a_c\  = M_L_CPU0_SA_DQS_DN<8>
  \dqs8_a_t||tdqs8_a_t\  = M_L_CPU0_SA_DQS_DP<8>
  VSS82  = GND
  DQ30_A  = M_L_CPU0_SA_DQ<30>
  VSS83  = GND
  DQ31_A  = M_L_CPU0_SA_DQ<31>
  VSS84  = GND
  CB2_A  = M_L_CPU0_SA_CB<2>
  VSS85  = GND
  CB3_A  = M_L_CPU0_SA_CB<3>
  VSS86  = GND
  \dqs9_a_c||tdqs9_a_c\  = M_L_CPU0_SA_DQS_DN<9>
  \dqs9_a_t||tdqs9_a_t\  = M_L_CPU0_SA_DQS_DP<9>
  VSS87  = GND
  CB6_A  = M_L_CPU0_SA_CB<6>
  VSS88  = GND
  CB7_A  = M_L_CPU0_SA_CB<7>
  VSS89  = GND
  RESET_N  = M_L_CPU0_RESET_N
  VSS90  = GND
  CS1_A_N  = M_L_CPU0_SA_CS_N<1>
  VSS91  = GND
  CA1_A  = M_L_CPU0_SA_CA<1>
  VSS92  = GND
  CA3_A  = M_L_CPU0_SA_CA<3>
  VSS93  = GND
  CA5_A  = M_L_CPU0_SA_CA<5>
  VSS94  = GND
  CK_T  = M_L_CPU0_CLK_DP<0>
  CK_C  = M_L_CPU0_CLK_DN<0>
  VSS95  = GND
  RFU4  = NC
  CA1_B  = M_L_CPU0_SB_CA<1>
  VSS96  = GND
  CA3_B  = M_L_CPU0_SB_CA<3>
  VSS97  = GND
  CA5_B  = M_L_CPU0_SB_CA<5>
  VSS98  = GND
  PAR_B  = M_L_CPU0_SB_PAR
  VSS99  = GND
  CS1_B_N  = M_L_CPU0_SB_CS_N<1>
  VSS100  = GND
  RFU5  = NC
  RFU6  = NC
  VSS101  = GND
  CB6_B  = M_L_CPU0_SB_CB<6>
  VSS102  = GND
  CB7_B  = M_L_CPU0_SB_CB<7>
  VSS103  = GND
  DQS4_B_C  = M_L_CPU0_SB_DQS_DN<4>
  DQS4_B_T  = M_L_CPU0_SB_DQS_DP<4>
  VSS104  = GND
  CB2_B  = M_L_CPU0_SB_CB<2>
  VSS105  = GND
  CB3_B  = M_L_CPU0_SB_CB<3>
  VSS106  = GND
  DQ2_B  = M_L_CPU0_SB_DQ<2>
  VSS107  = GND
  DQ3_B  = M_L_CPU0_SB_DQ<3>
  VSS108  = GND
  \dqs5_b_c||tdqs5_b_c\  = M_L_CPU0_SB_DQS_DN<5>
  \dqs5_b_t||tdqs5_b_t\  = M_L_CPU0_SB_DQS_DP<5>
  VSS109  = GND
  DQ6_B  = M_L_CPU0_SB_DQ<6>
  VSS110  = GND
  DQ7_B  = M_L_CPU0_SB_DQ<7>
  VSS111  = GND
  DQ10_B  = M_L_CPU0_SB_DQ<10>
  VSS112  = GND
  DQ11_B  = M_L_CPU0_SB_DQ<11>
  VSS113  = GND
  \dqs6_b_c||tdqs6_b_c\  = M_L_CPU0_SB_DQS_DN<6>
  \dqs6_b_t||tdqs6_b_t\  = M_L_CPU0_SB_DQS_DP<6>
  VSS114  = GND
  DQ14_B  = M_L_CPU0_SB_DQ<14>
  VSS115  = GND
  DQ15_B  = M_L_CPU0_SB_DQ<15>
  VSS116  = GND
  DQ18_B  = M_L_CPU0_SB_DQ<18>
  VSS117  = GND
  DQ19_B  = M_L_CPU0_SB_DQ<19>
  VSS118  = GND
  \dqs7_b_c||tdqs7_b_c\  = M_L_CPU0_SB_DQS_DN<7>
  \dqs7_b_t||tdqs7_b_t\  = M_L_CPU0_SB_DQS_DP<7>
  VSS119  = GND
  DQ22_B  = M_L_CPU0_SB_DQ<22>
  VSS120  = GND
  DQ23_B  = M_L_CPU0_SB_DQ<23>
  VSS121  = GND
  DQ26_B  = M_L_CPU0_SB_DQ<26>
  VSS122  = GND
  DQ27_B  = M_L_CPU0_SB_DQ<27>
  VSS123  = GND
  \dqs8_b_c||tdqs8_b_c\  = M_L_CPU0_SB_DQS_DN<8>
  \dqs8_b_t||tdqs8_b_t\  = M_L_CPU0_SB_DQS_DP<8>
  VSS124  = GND
  DQ30_B  = M_L_CPU0_SB_DQ<30>
  VSS125  = GND
  DQ31_B  = M_L_CPU0_SB_DQ<31>
  VSS126  = GND
  G1  = GND
  G2  = GND
  G3  = GND

(kicad_pcb
	(version 20260206)
	(generator "pcbnew")
	(generator_version "10.0")
	(general
		(thickness 1.6)
		(legacy_teardrops no)
	)
	(paper "A4")
	(title_block
		(title "04192023_DAF0TMB3IC0_F0TG_MB_C_brd_V02_OCP.brd")
		(comment 1 "Grand Teton / footprint 3721 of 8354 (J67), pads 1-46 of 291")
	)
	(layers
		(0 "F.Cu" signal "TOP")
		(4 "In1.Cu" signal "GND")
		(6 "In2.Cu" signal "IN1")
		(8 "In3.Cu" signal "GND1")
		(10 "In4.Cu" signal "IN2")
		(12 "In5.Cu" signal "GND2")
		(14 "In6.Cu" signal "IN3")
		(16 "In7.Cu" signal "GND3")
		(18 "In8.Cu" signal "VCC")
		(20 "In9.Cu" signal "VCC1")
		(22 "In10.Cu" signal "GND4")
		(24 "In11.Cu" signal "IN4")
		(26 "In12.Cu" signal "GND5")
		(28 "In13.Cu" signal "IN5")
		(30 "In14.Cu" signal "GND6")
		(32 "In15.Cu" signal "IN6")
		(34 "In16.Cu" signal "GND7")
		(2 "B.Cu" signal "BOTTOM")
		(9 "F.Adhes" user "F.Adhesive")
		(11 "B.Adhes" user "B.Adhesive")
		(13 "F.Paste" user "Package Geometry/Pastemask Top")
		(15 "B.Paste" user "Package Geometry/Pastemask Bottom")
		(5 "F.SilkS" user "Ref Des/Silkscreen Top")
		(7 "B.SilkS" user "Ref Des/Silkscreen Bottom")
		(1 "F.Mask" user "Board Geometry/Soldermask Top")
		(3 "B.Mask" user "Board Geometry/Soldermask Bottom")
		(17 "Dwgs.User" user "User.Drawings")
		(19 "Cmts.User" user "User.Comments")
		(21 "Eco1.User" user "User.Eco1")
		(23 "Eco2.User" user "User.Eco2")
		(25 "Edge.Cuts" user "Board Geometry/Outline")
		(27 "Margin" user)
		(31 "F.CrtYd" user "Package Geometry/Place Bound Top")
		(29 "B.CrtYd" user "Package Geometry/Place Bound Bottom")
		(35 "F.Fab" user "Ref Des/Assembly Top")
		(33 "B.Fab" user "Ref Des/Assembly Bottom")
	)
	(footprint ""
		(layer "F.Cu")
		(at 452.138034 -255.560068 180)
		(property "Reference" "J67"
			(at 2.380488 -81.709768 0)
			(unlocked yes)
			(layer "F.SilkS")
			(effects
				(font
					(size 0.7874 0.5842)
					(thickness 0.1524)
				)
			)
		)
		(property "Value" ""
			(at 0 0 180)
			(layer "F.Fab")
			(effects
				(font
					(size 1.27 1.27)
				)
			)
		)
		(duplicate_pad_numbers_are_jumpers no)
		(pad "1" smd rect
			(at -2.050034 -63.324994 90)
			(size 0.519938 1.4986)
			(layers "F.Cu" "F.Mask" "F.Paste")
			(net "P12V_MEM_CPU0")
		)
		(pad "2" smd rect
			(at -2.050034 -62.47511 90)
			(size 0.519938 1.4986)
			(layers "F.Cu" "F.Mask" "F.Paste")
			(net "Net_2403")
		)
		(pad "3" smd rect
			(at -2.050034 -61.624972 90)
			(size 0.519938 1.4986)
			(layers "F.Cu" "F.Mask" "F.Paste")
			(net "P3V3_AUX")
		)
		(pad "4" smd rect
			(at -2.050034 -60.775088 90)
			(size 0.519938 1.4986)
			(layers "F.Cu" "F.Mask" "F.Paste")
			(net "I3C_SPD_DDRL_CPU0_SCL")
		)
		(pad "5" smd rect
			(at -2.050034 -59.92495 90)
			(size 0.519938 1.4986)
			(layers "F.Cu" "F.Mask" "F.Paste")
			(net "I3C_SPD_DDRL_CPU0_SDA")
		)
		(pad "6" smd rect
			(at -2.050034 -59.075066 90)
			(size 0.519938 1.4986)
			(layers "F.Cu" "F.Mask" "F.Paste")
			(net "GND")
		)
		(pad "7" smd rect
			(at -2.050034 -58.224928 90)
			(size 0.519938 1.4986)
			(layers "F.Cu" "F.Mask" "F.Paste")
			(net "M_L_CPU0_SA_DQ<0>")
		)
		(pad "8" smd rect
			(at -2.050034 -57.375044 90)
			(size 0.519938 1.4986)
			(layers "F.Cu" "F.Mask" "F.Paste")
			(net "GND")
		)
		(pad "9" smd rect
			(at -2.050034 -56.524906 90)
			(size 0.519938 1.4986)
			(layers "F.Cu" "F.Mask" "F.Paste")
			(net "M_L_CPU0_SA_DQ<1>")
		)
		(pad "10" smd rect
			(at -2.050034 -55.675022 90)
			(size 0.519938 1.4986)
			(layers "F.Cu" "F.Mask" "F.Paste")
			(net "GND")
		)
		(pad "11" smd rect
			(at -2.050034 -54.824884 90)
			(size 0.519938 1.4986)
			(layers "F.Cu" "F.Mask" "F.Paste")
			(net "M_L_CPU0_SA_DQS_DP<0>")
		)
		(pad "12" smd rect
			(at -2.050034 -53.975 90)
			(size 0.519938 1.4986)
			(layers "F.Cu" "F.Mask" "F.Paste")
			(net "M_L_CPU0_SA_DQS_DN<0>")
		)
		(pad "13" smd rect
			(at -2.050034 -53.125116 90)
			(size 0.519938 1.4986)
			(layers "F.Cu" "F.Mask" "F.Paste")
			(net "GND")
		)
		(pad "14" smd rect
			(at -2.050034 -52.274978 90)
			(size 0.519938 1.4986)
			(layers "F.Cu" "F.Mask" "F.Paste")
			(net "M_L_CPU0_SA_DQ<4>")
		)
		(pad "15" smd rect
			(at -2.050034 -51.425094 90)
			(size 0.519938 1.4986)
			(layers "F.Cu" "F.Mask" "F.Paste")
			(net "GND")
		)
		(pad "16" smd rect
			(at -2.050034 -50.574956 90)
			(size 0.519938 1.4986)
			(layers "F.Cu" "F.Mask" "F.Paste")
			(net "M_L_CPU0_SA_DQ<5>")
		)
		(pad "17" smd rect
			(at -2.050034 -49.725072 90)
			(size 0.519938 1.4986)
			(layers "F.Cu" "F.Mask" "F.Paste")
			(net "GND")
		)
		(pad "18" smd rect
			(at -2.050034 -48.874934 90)
			(size 0.519938 1.4986)
			(layers "F.Cu" "F.Mask" "F.Paste")
			(net "M_L_CPU0_SA_DQ<8>")
		)
		(pad "19" smd rect
			(at -2.050034 -48.02505 90)
			(size 0.519938 1.4986)
			(layers "F.Cu" "F.Mask" "F.Paste")
			(net "GND")
		)
		(pad "20" smd rect
			(at -2.050034 -47.174912 90)
			(size 0.519938 1.4986)
			(layers "F.Cu" "F.Mask" "F.Paste")
			(net "M_L_CPU0_SA_DQ<9>")
		)
		(pad "21" smd rect
			(at -2.050034 -46.325028 90)
			(size 0.519938 1.4986)
			(layers "F.Cu" "F.Mask" "F.Paste")
			(net "GND")
		)
		(pad "22" smd rect
			(at -2.050034 -45.47489 90)
			(size 0.519938 1.4986)
			(layers "F.Cu" "F.Mask" "F.Paste")
			(net "M_L_CPU0_SA_DQS_DP<1>")
		)
		(pad "23" smd rect
			(at -2.050034 -44.625006 90)
			(size 0.519938 1.4986)
			(layers "F.Cu" "F.Mask" "F.Paste")
			(net "M_L_CPU0_SA_DQS_DN<1>")
		)
		(pad "24" smd rect
			(at -2.050034 -43.775122 90)
			(size 0.519938 1.4986)
			(layers "F.Cu" "F.Mask" "F.Paste")
			(net "GND")
		)
		(pad "25" smd rect
			(at -2.050034 -42.924984 90)
			(size 0.519938 1.4986)
			(layers "F.Cu" "F.Mask" "F.Paste")
			(net "M_L_CPU0_SA_DQ<12>")
		)
		(pad "26" smd rect
			(at -2.050034 -42.0751 90)
			(size 0.519938 1.4986)
			(layers "F.Cu" "F.Mask" "F.Paste")
			(net "GND")
		)
		(pad "27" smd rect
			(at -2.050034 -41.224962 90)
			(size 0.519938 1.4986)
			(layers "F.Cu" "F.Mask" "F.Paste")
			(net "M_L_CPU0_SA_DQ<13>")
		)
		(pad "28" smd rect
			(at -2.050034 -40.375078 90)
			(size 0.519938 1.4986)
			(layers "F.Cu" "F.Mask" "F.Paste")
			(net "GND")
		)
		(pad "29" smd rect
			(at -2.050034 -39.52494 90)
			(size 0.519938 1.4986)
			(layers "F.Cu" "F.Mask" "F.Paste")
			(net "M_L_CPU0_SA_DQ<16>")
		)
		(pad "30" smd rect
			(at -2.050034 -38.675056 90)
			(size 0.519938 1.4986)
			(layers "F.Cu" "F.Mask" "F.Paste")
			(net "GND")
		)
		(pad "31" smd rect
			(at -2.050034 -37.824918 90)
			(size 0.519938 1.4986)
			(layers "F.Cu" "F.Mask" "F.Paste")
			(net "M_L_CPU0_SA_DQ<17>")
		)
		(pad "32" smd rect
			(at -2.050034 -36.975034 90)
			(size 0.519938 1.4986)
			(layers "F.Cu" "F.Mask" "F.Paste")
			(net "GND")
		)
		(pad "33" smd rect
			(at -2.050034 -36.124896 90)
			(size 0.519938 1.4986)
			(layers "F.Cu" "F.Mask" "F.Paste")
			(net "M_L_CPU0_SA_DQS_DP<2>")
		)
		(pad "34" smd rect
			(at -2.050034 -35.275012 90)
			(size 0.519938 1.4986)
			(layers "F.Cu" "F.Mask" "F.Paste")
			(net "M_L_CPU0_SA_DQS_DN<2>")
		)
		(pad "35" smd rect
			(at -2.050034 -34.425128 90)
			(size 0.519938 1.4986)
			(layers "F.Cu" "F.Mask" "F.Paste")
			(net "GND")
		)
		(pad "36" smd rect
			(at -2.050034 -33.57499 90)
			(size 0.519938 1.4986)
			(layers "F.Cu" "F.Mask" "F.Paste")
			(net "M_L_CPU0_SA_DQ<20>")
		)
		(pad "37" smd rect
			(at -2.050034 -32.725106 90)
			(size 0.519938 1.4986)
			(layers "F.Cu" "F.Mask" "F.Paste")
			(net "GND")
		)
		(pad "38" smd rect
			(at -2.050034 -31.874968 90)
			(size 0.519938 1.4986)
			(layers "F.Cu" "F.Mask" "F.Paste")
			(net "M_L_CPU0_SA_DQ<21>")
		)
		(pad "39" smd rect
			(at -2.050034 -31.025084 90)
			(size 0.519938 1.4986)
			(layers "F.Cu" "F.Mask" "F.Paste")
			(net "GND")
		)
		(pad "40" smd rect
			(at -2.050034 -30.174946 90)
			(size 0.519938 1.4986)
			(layers "F.Cu" "F.Mask" "F.Paste")
			(net "M_L_CPU0_SA_DQ<24>")
		)
		(pad "41" smd rect
			(at -2.050034 -29.325062 90)
			(size 0.519938 1.4986)
			(layers "F.Cu" "F.Mask" "F.Paste")
			(net "GND")
		)
		(pad "42" smd rect
			(at -2.050034 -28.474924 90)
			(size 0.519938 1.4986)
			(layers "F.Cu" "F.Mask" "F.Paste")
			(net "M_L_CPU0_SA_DQ<25>")
		)
		(pad "43" smd rect
			(at -2.050034 -27.62504 90)
			(size 0.519938 1.4986)
			(layers "F.Cu" "F.Mask" "F.Paste")
			(net "GND")
		)
		(pad "44" smd rect
			(at -2.050034 -26.774902 90)
			(size 0.519938 1.4986)
			(layers "F.Cu" "F.Mask" "F.Paste")
			(net "M_L_CPU0_SA_DQS_DP<3>")
		)
		(pad "45" smd rect
			(at -2.050034 -25.925018 90)
			(size 0.519938 1.4986)
			(layers "F.Cu" "F.Mask" "F.Paste")
			(net "M_L_CPU0_SA_DQS_DN<3>")
		)
		(pad "46" smd rect
			(at -2.050034 -25.07488 90)
			(size 0.519938 1.4986)
			(layers "F.Cu" "F.Mask" "F.Paste")
			(net "GND")
		)
	)
)
